(kicad_pcb
	(version 20260206)
	(generator "pcbnew")
	(generator_version "10.0")
	(general
		(thickness 1.6)
		(legacy_teardrops no)
	)
	(paper "A4")
	(title_block
		(title "04192023_DAF0TMB3IC0_F0TG_MB_C_brd_V02_OCP.brd")
		(comment 1 "Grand Teton / footprints 656-661 of 8354")
	)
	(layers
		(0 "F.Cu" signal "TOP")
		(4 "In1.Cu" signal "GND")
		(6 "In2.Cu" signal "IN1")
		(8 "In3.Cu" signal "GND1")
		(10 "In4.Cu" signal "IN2")
		(12 "In5.Cu" signal "GND2")
		(14 "In6.Cu" signal "IN3")
		(16 "In7.Cu" signal "GND3")
		(18 "In8.Cu" signal "VCC")
		(20 "In9.Cu" signal "VCC1")
		(22 "In10.Cu" signal "GND4")
		(24 "In11.Cu" signal "IN4")
		(26 "In12.Cu" signal "GND5")
		(28 "In13.Cu" signal "IN5")
		(30 "In14.Cu" signal "GND6")
		(32 "In15.Cu" signal "IN6")
		(34 "In16.Cu" signal "GND7")
		(2 "B.Cu" signal "BOTTOM")
		(9 "F.Adhes" user "F.Adhesive")
		(11 "B.Adhes" user "B.Adhesive")
		(13 "F.Paste" user "Package Geometry/Pastemask Top")
		(15 "B.Paste" user "Package Geometry/Pastemask Bottom")
		(5 "F.SilkS" user "Ref Des/Silkscreen Top")
		(7 "B.SilkS" user "Ref Des/Silkscreen Bottom")
		(1 "F.Mask" user "Board Geometry/Soldermask Top")
		(3 "B.Mask" user "Board Geometry/Soldermask Bottom")
		(17 "Dwgs.User" user "User.Drawings")
		(19 "Cmts.User" user "User.Comments")
		(21 "Eco1.User" user "User.Eco1")
		(23 "Eco2.User" user "User.Eco2")
		(25 "Edge.Cuts" user "Board Geometry/Outline")
		(27 "Margin" user)
		(31 "F.CrtYd" user "Package Geometry/Place Bound Top")
		(29 "B.CrtYd" user "Package Geometry/Place Bound Bottom")
		(35 "F.Fab" user "Ref Des/Assembly Top")
		(33 "B.Fab" user "Ref Des/Assembly Bottom")
	)
	(footprint ""
		(layer "F.Cu")
		(at 288.393124 -13.360146)
		(property "Reference" "R4214"
			(at 0 0 0)
			(layer "F.SilkS")
			(hide yes)
			(effects
				(font
					(size 1.27 1.27)
				)
			)
		)
		(property "Value" ""
			(at 0 0 0)
			(layer "F.Fab")
			(effects
				(font
					(size 1.27 1.27)
				)
			)
		)
		(duplicate_pad_numbers_are_jumpers no)
		(fp_line
			(start -0.7874 -0.4064)
			(end 0.7874 -0.4064)
			(stroke
				(width 0.1524)
				(type default)
			)
			(layer "F.SilkS")
		)
		(fp_line
			(start -0.7874 0.4064)
			(end -0.7874 -0.4064)
			(stroke
				(width 0.1524)
				(type default)
			)
			(layer "F.SilkS")
		)
		(fp_line
			(start 0.7874 -0.4064)
			(end 0.7874 0.4064)
			(stroke
				(width 0.1524)
				(type default)
			)
			(layer "F.SilkS")
		)
		(fp_line
			(start 0.7874 0.4064)
			(end -0.7874 0.4064)
			(stroke
				(width 0.1524)
				(type default)
			)
			(layer "F.SilkS")
		)
		(fp_line
			(start -0.67945 -0.305054)
			(end -0.12065 -0.305054)
			(stroke
				(width 0.1)
				(type default)
			)
			(layer "F.Fab")
		)
		(fp_line
			(start -0.67945 0.3048)
			(end -0.67945 -0.305054)
			(stroke
				(width 0.1)
				(type default)
			)
			(layer "F.Fab")
		)
		(fp_line
			(start -0.12065 -0.305054)
			(end -0.12065 -0.2794)
			(stroke
				(width 0.1)
				(type default)
			)
			(layer "F.Fab")
		)
		(fp_line
			(start -0.12065 -0.2794)
			(end 0.12065 -0.2794)
			(stroke
				(width 0.1)
				(type default)
			)
			(layer "F.Fab")
		)
		(fp_line
			(start -0.12065 0.2794)
			(end -0.12065 0.3048)
			(stroke
				(width 0.1)
				(type default)
			)
			(layer "F.Fab")
		)
		(fp_line
			(start -0.12065 0.3048)
			(end -0.67945 0.3048)
			(stroke
				(width 0.1)
				(type default)
			)
			(layer "F.Fab")
		)
		(fp_line
			(start 0.120396 0.2794)
			(end -0.12065 0.2794)
			(stroke
				(width 0.1)
				(type default)
			)
			(layer "F.Fab")
		)
		(fp_line
			(start 0.120396 0.3048)
			(end 0.120396 0.2794)
			(stroke
				(width 0.1)
				(type default)
			)
			(layer "F.Fab")
		)
		(fp_line
			(start 0.12065 -0.3048)
			(end 0.67945 -0.3048)
			(stroke
				(width 0.1)
				(type default)
			)
			(layer "F.Fab")
		)
		(fp_line
			(start 0.12065 -0.2794)
			(end 0.12065 -0.3048)
			(stroke
				(width 0.1)
				(type default)
			)
			(layer "F.Fab")
		)
		(fp_line
			(start 0.67945 -0.3048)
			(end 0.67945 0.3048)
			(stroke
				(width 0.1)
				(type default)
			)
			(layer "F.Fab")
		)
		(fp_line
			(start 0.67945 0.3048)
			(end 0.120396 0.3048)
			(stroke
				(width 0.1)
				(type default)
			)
			(layer "F.Fab")
		)
		(pad "1" smd circle
			(at -0.40005 0)
			(size 0 0)
			(layers "F.Cu" "F.Mask" "F.Paste")
			(net "FM_THERMAL_ALERT_N")
		)
		(pad "2" smd circle
			(at 0.40005 0)
			(size 0 0)
			(layers "F.Cu" "F.Mask" "F.Paste")
			(net "FM_G751_1_ALERT_N")
		)
	)
	(footprint ""
		(layer "F.Cu")
		(at 177.67808 -92.685616 -90)
		(property "Reference" "R6744"
			(at 0 0 270)
			(layer "F.SilkS")
			(hide yes)
			(effects
				(font
					(size 1.27 1.27)
				)
			)
		)
		(property "Value" ""
			(at 0 0 270)
			(layer "F.Fab")
			(effects
				(font
					(size 1.27 1.27)
				)
			)
		)
		(duplicate_pad_numbers_are_jumpers no)
		(fp_line
			(start -0.7874 0.4064)
			(end -0.7874 -0.4064)
			(stroke
				(width 0.1524)
				(type default)
			)
			(layer "F.SilkS")
		)
		(fp_line
			(start 0.7874 0.4064)
			(end -0.7874 0.4064)
			(stroke
				(width 0.1524)
				(type default)
			)
			(layer "F.SilkS")
		)
		(fp_line
			(start -0.7874 -0.4064)
			(end 0.7874 -0.4064)
			(stroke
				(width 0.1524)
				(type default)
			)
			(layer "F.SilkS")
		)
		(fp_line
			(start 0.7874 -0.4064)
			(end 0.7874 0.4064)
			(stroke
				(width 0.1524)
				(type default)
			)
			(layer "F.SilkS")
		)
		(fp_line
			(start -0.67945 0.3048)
			(end -0.67945 -0.305054)
			(stroke
				(width 0.1)
				(type default)
			)
			(layer "F.Fab")
		)
		(fp_line
			(start -0.12065 0.3048)
			(end -0.67945 0.3048)
			(stroke
				(width 0.1)
				(type default)
			)
			(layer "F.Fab")
		)
		(fp_line
			(start 0.120396 0.3048)
			(end 0.120396 0.2794)
			(stroke
				(width 0.1)
				(type default)
			)
			(layer "F.Fab")
		)
		(fp_line
			(start 0.67945 0.3048)
			(end 0.120396 0.3048)
			(stroke
				(width 0.1)
				(type default)
			)
			(layer "F.Fab")
		)
		(fp_line
			(start -0.12065 0.2794)
			(end -0.12065 0.3048)
			(stroke
				(width 0.1)
				(type default)
			)
			(layer "F.Fab")
		)
		(fp_line
			(start 0.120396 0.2794)
			(end -0.12065 0.2794)
			(stroke
				(width 0.1)
				(type default)
			)
			(layer "F.Fab")
		)
		(fp_line
			(start -0.12065 -0.2794)
			(end 0.12065 -0.2794)
			(stroke
				(width 0.1)
				(type default)
			)
			(layer "F.Fab")
		)
		(fp_line
			(start 0.12065 -0.2794)
			(end 0.12065 -0.3048)
			(stroke
				(width 0.1)
				(type default)
			)
			(layer "F.Fab")
		)
		(fp_line
			(start 0.12065 -0.3048)
			(end 0.67945 -0.3048)
			(stroke
				(width 0.1)
				(type default)
			)
			(layer "F.Fab")
		)
		(fp_line
			(start 0.67945 -0.3048)
			(end 0.67945 0.3048)
			(stroke
				(width 0.1)
				(type default)
			)
			(layer "F.Fab")
		)
		(fp_line
			(start -0.67945 -0.305054)
			(end -0.12065 -0.305054)
			(stroke
				(width 0.1)
				(type default)
			)
			(layer "F.Fab")
		)
		(fp_line
			(start -0.12065 -0.305054)
			(end -0.12065 -0.2794)
			(stroke
				(width 0.1)
				(type default)
			)
			(layer "F.Fab")
		)
		(pad "1" smd circle
			(at -0.40005 0 270)
			(size 0 0)
			(layers "F.Cu" "F.Mask" "F.Paste")
			(net "RT_BOARD_ID_ID1")
		)
		(pad "2" smd circle
			(at 0.40005 0 270)
			(size 0 0)
			(layers "F.Cu" "F.Mask" "F.Paste")
			(net "GND")
		)
	)
	(footprint ""
		(layer "F.Cu")
		(at 353.900232 -262.204962 180)
		(property "Reference" "C2627"
			(at 0 0 180)
			(layer "F.SilkS")
			(hide yes)
			(effects
				(font
					(size 1.27 1.27)
				)
			)
		)
		(property "Value" ""
			(at 0 0 180)
			(layer "F.Fab")
			(effects
				(font
					(size 1.27 1.27)
				)
			)
		)
		(duplicate_pad_numbers_are_jumpers no)
		(fp_line
			(start 0.7874 0.4064)
			(end -0.7874 0.4064)
			(stroke
				(width 0.1524)
				(type default)
			)
			(layer "F.SilkS")
		)
		(fp_line
			(start 0.7874 -0.4064)
			(end 0.7874 0.4064)
			(stroke
				(width 0.1524)
				(type default)
			)
			(layer "F.SilkS")
		)
		(fp_line
			(start -0.7874 0.4064)
			(end -0.7874 -0.4064)
			(stroke
				(width 0.1524)
				(type default)
			)
			(layer "F.SilkS")
		)
		(fp_line
			(start -0.7874 -0.4064)
			(end 0.7874 -0.4064)
			(stroke
				(width 0.1524)
				(type default)
			)
			(layer "F.SilkS")
		)
		(fp_line
			(start 0.67945 0.3048)
			(end 0.120396 0.3048)
			(stroke
				(width 0.1)
				(type default)
			)
			(layer "F.Fab")
		)
		(fp_line
			(start 0.67945 -0.3048)
			(end 0.67945 0.3048)
			(stroke
				(width 0.1)
				(type default)
			)
			(layer "F.Fab")
		)
		(fp_line
			(start 0.12065 -0.2794)
			(end 0.12065 -0.3048)
			(stroke
				(width 0.1)
				(type default)
			)
			(layer "F.Fab")
		)
		(fp_line
			(start 0.12065 -0.3048)
			(end 0.67945 -0.3048)
			(stroke
				(width 0.1)
				(type default)
			)
			(layer "F.Fab")
		)
		(fp_line
			(start 0.120396 0.3048)
			(end 0.120396 0.2794)
			(stroke
				(width 0.1)
				(type default)
			)
			(layer "F.Fab")
		)
		(fp_line
			(start 0.120396 0.2794)
			(end -0.12065 0.2794)
			(stroke
				(width 0.1)
				(type default)
			)
			(layer "F.Fab")
		)
		(fp_line
			(start -0.12065 0.3048)
			(end -0.67945 0.3048)
			(stroke
				(width 0.1)
				(type default)
			)
			(layer "F.Fab")
		)
		(fp_line
			(start -0.12065 0.2794)
			(end -0.12065 0.3048)
			(stroke
				(width 0.1)
				(type default)
			)
			(layer "F.Fab")
		)
		(fp_line
			(start -0.12065 -0.2794)
			(end 0.12065 -0.2794)
			(stroke
				(width 0.1)
				(type default)
			)
			(layer "F.Fab")
		)
		(fp_line
			(start -0.12065 -0.305054)
			(end -0.12065 -0.2794)
			(stroke
				(width 0.1)
				(type default)
			)
			(layer "F.Fab")
		)
		(fp_line
			(start -0.67945 0.3048)
			(end -0.67945 -0.305054)
			(stroke
				(width 0.1)
				(type default)
			)
			(layer "F.Fab")
		)
		(fp_line
			(start -0.67945 -0.305054)
			(end -0.12065 -0.305054)
			(stroke
				(width 0.1)
				(type default)
			)
			(layer "F.Fab")
		)
		(pad "1" smd circle
			(at -0.40005 0 180)
			(size 0 0)
			(layers "F.Cu" "F.Mask" "F.Paste")
			(net "PVDD11_S3_P0")
		)
		(pad "2" smd circle
			(at 0.40005 0 180)
			(size 0 0)
			(layers "F.Cu" "F.Mask" "F.Paste")
			(net "GND")
		)
	)
	(footprint ""
		(layer "F.Cu")
		(at 439.029602 -421.37711)
		(property "Reference" "PR6817"
			(at 0 0 0)
			(layer "F.SilkS")
			(hide yes)
			(effects
				(font
					(size 1.27 1.27)
				)
			)
		)
		(property "Value" ""
			(at 0 0 0)
			(layer "F.Fab")
			(effects
				(font
					(size 1.27 1.27)
				)
			)
		)
		(duplicate_pad_numbers_are_jumpers no)
		(fp_line
			(start -0.7874 -0.4064)
			(end 0.7874 -0.4064)
			(stroke
				(width 0.1524)
				(type default)
			)
			(layer "F.SilkS")
		)
		(fp_line
			(start -0.7874 0.4064)
			(end -0.7874 -0.4064)
			(stroke
				(width 0.1524)
				(type default)
			)
			(layer "F.SilkS")
		)
		(fp_line
			(start 0.7874 -0.4064)
			(end 0.7874 0.4064)
			(stroke
				(width 0.1524)
				(type default)
			)
			(layer "F.SilkS")
		)
		(fp_line
			(start 0.7874 0.4064)
			(end -0.7874 0.4064)
			(stroke
				(width 0.1524)
				(type default)
			)
			(layer "F.SilkS")
		)
		(fp_line
			(start -0.67945 -0.305054)
			(end -0.12065 -0.305054)
			(stroke
				(width 0.1)
				(type default)
			)
			(layer "F.Fab")
		)
		(fp_line
			(start -0.67945 0.3048)
			(end -0.67945 -0.305054)
			(stroke
				(width 0.1)
				(type default)
			)
			(layer "F.Fab")
		)
		(fp_line
			(start -0.12065 -0.305054)
			(end -0.12065 -0.2794)
			(stroke
				(width 0.1)
				(type default)
			)
			(layer "F.Fab")
		)
		(fp_line
			(start -0.12065 -0.2794)
			(end 0.12065 -0.2794)
			(stroke
				(width 0.1)
				(type default)
			)
			(layer "F.Fab")
		)
		(fp_line
			(start -0.12065 0.2794)
			(end -0.12065 0.3048)
			(stroke
				(width 0.1)
				(type default)
			)
			(layer "F.Fab")
		)
		(fp_line
			(start -0.12065 0.3048)
			(end -0.67945 0.3048)
			(stroke
				(width 0.1)
				(type default)
			)
			(layer "F.Fab")
		)
		(fp_line
			(start 0.120396 0.2794)
			(end -0.12065 0.2794)
			(stroke
				(width 0.1)
				(type default)
			)
			(layer "F.Fab")
		)
		(fp_line
			(start 0.120396 0.3048)
			(end 0.120396 0.2794)
			(stroke
				(width 0.1)
				(type default)
			)
			(layer "F.Fab")
		)
		(fp_line
			(start 0.12065 -0.3048)
			(end 0.67945 -0.3048)
			(stroke
				(width 0.1)
				(type default)
			)
			(layer "F.Fab")
		)
		(fp_line
			(start 0.12065 -0.2794)
			(end 0.12065 -0.3048)
			(stroke
				(width 0.1)
				(type default)
			)
			(layer "F.Fab")
		)
		(fp_line
			(start 0.67945 -0.3048)
			(end 0.67945 0.3048)
			(stroke
				(width 0.1)
				(type default)
			)
			(layer "F.Fab")
		)
		(fp_line
			(start 0.67945 0.3048)
			(end 0.120396 0.3048)
			(stroke
				(width 0.1)
				(type default)
			)
			(layer "F.Fab")
		)
		(pad "1" smd circle
			(at -0.40005 0)
			(size 0 0)
			(layers "F.Cu" "F.Mask" "F.Paste")
			(net "P3V3_AUX")
		)
		(pad "2" smd circle
			(at 0.40005 0)
			(size 0 0)
			(layers "F.Cu" "F.Mask" "F.Paste")
			(net "TP_P0V9_RETIMER_CPU0_SVID_ALERT_N")
		)
	)
	(footprint ""
		(layer "F.Cu")
		(at 81.424018 -15.177262 180)
		(property "Reference" "PD108"
			(at -5.42798 0.894588 0)
			(unlocked yes)
			(layer "F.SilkS")
			(effects
				(font
					(size 0.7874 0.5842)
					(thickness 0.1524)
				)
				(justify left)
			)
		)
		(property "Value" ""
			(at 0 0 180)
			(layer "F.Fab")
			(effects
				(font
					(size 1.27 1.27)
				)
			)
		)
		(duplicate_pad_numbers_are_jumpers no)
		(fp_line
			(start 4.107942 1.459992)
			(end -3.400044 1.459992)
			(stroke
				(width 0.1524)
				(type default)
			)
			(layer "F.SilkS")
		)
		(fp_line
			(start 4.107942 -1.459992)
			(end 4.107942 1.459992)
			(stroke
				(width 0.1524)
				(type default)
			)
			(layer "F.SilkS")
		)
		(fp_line
			(start -3.400044 1.459992)
			(end -3.400044 -1.459992)
			(stroke
				(width 0.1524)
				(type default)
			)
			(layer "F.SilkS")
		)
		(fp_line
			(start -3.400044 -1.459992)
			(end 4.107942 -1.459992)
			(stroke
				(width 0.1524)
				(type default)
			)
			(layer "F.SilkS")
		)
		(fp_rect
			(start 4.107942 -1.459992)
			(end 3.308096 1.459992)
			(stroke
				(width 0)
				(type default)
			)
			(fill yes)
			(layer "F.SilkS")
		)
		(fp_line
			(start 2.29997 1.459992)
			(end -2.29997 1.459992)
			(stroke
				(width 0.1)
				(type default)
			)
			(layer "F.Fab")
		)
		(fp_line
			(start 2.29997 -1.459992)
			(end 2.29997 1.459992)
			(stroke
				(width 0.1)
				(type default)
			)
			(layer "F.Fab")
		)
		(fp_line
			(start -2.29997 1.459992)
			(end -2.29997 -1.459992)
			(stroke
				(width 0.1)
				(type default)
			)
			(layer "F.Fab")
		)
		(fp_line
			(start -2.29997 -1.459992)
			(end 2.29997 -1.459992)
			(stroke
				(width 0.1)
				(type default)
			)
			(layer "F.Fab")
		)
		(fp_text user "-"
			(at 5.4102 0.29845 0)
			(unlocked yes)
			(layer "F.SilkS")
			(effects
				(font
					(size 1.905 1.4224)
					(thickness 0.1524)
				)
				(justify left)
			)
		)
		(fp_text user "+"
			(at -4.7752 -0.12065 180)
			(unlocked yes)
			(layer "F.SilkS")
			(effects
				(font
					(size 1.905 1.4224)
					(thickness 0.1524)
				)
				(justify left)
			)
		)
		(fp_text user "-"
			(at 5.4102 0.29845 0)
			(unlocked yes)
			(layer "F.Fab")
			(effects
				(font
					(size 1.905 1.4224)
					(thickness 0.1524)
				)
				(justify left)
			)
		)
		(fp_text user "+"
			(at -4.7752 -0.12065 180)
			(unlocked yes)
			(layer "F.Fab")
			(effects
				(font
					(size 1.905 1.4224)
					(thickness 0.1524)
				)
				(justify left)
			)
		)
		(pad "A" smd rect
			(at -1.999996 0 270)
			(size 1.7018 2.5146)
			(layers "F.Cu" "F.Mask" "F.Paste")
			(net "GND")
		)
		(pad "C" smd rect
			(at 1.999996 0 270)
			(size 1.7018 2.5146)
			(layers "F.Cu" "F.Mask" "F.Paste")
			(net "P12V_OCP_V3_2")
		)
	)
	(footprint ""
		(layer "F.Cu")
		(at 336.195416 -20.136612 -90)
		(property "Reference" "Q29"
			(at -0.557276 2.35966 90)
			(unlocked yes)
			(layer "F.SilkS")
			(effects
				(font
					(size 0.7874 0.5842)
					(thickness 0.1524)
				)
			)
		)
		(property "Value" ""
			(at 0 0 270)
			(layer "F.Fab")
			(effects
				(font
					(size 1.27 1.27)
				)
			)
		)
		(duplicate_pad_numbers_are_jumpers no)
		(fp_line
			(start -1.8796 1.651)
			(end -1.8796 -1.651)
			(stroke
				(width 0.1524)
				(type default)
			)
			(layer "F.SilkS")
		)
		(fp_line
			(start 1.8796 1.651)
			(end -1.8796 1.651)
			(stroke
				(width 0.1524)
				(type default)
			)
			(layer "F.SilkS")
		)
		(fp_line
			(start -1.8796 -1.651)
			(end 1.8796 -1.651)
			(stroke
				(width 0.1524)
				(type default)
			)
			(layer "F.SilkS")
		)
		(fp_line
			(start 1.8796 -1.651)
			(end 1.8796 1.651)
			(stroke
				(width 0.1524)
				(type default)
			)
			(layer "F.SilkS")
		)
		(fp_line
			(start -0.700024 1.500124)
			(end -0.700024 -1.500124)
			(stroke
				(width 0.1)
				(type default)
			)
			(layer "F.Fab")
		)
		(fp_line
			(start 0.700024 1.500124)
			(end -0.700024 1.500124)
			(stroke
				(width 0.1)
				(type default)
			)
			(layer "F.Fab")
		)
		(fp_line
			(start -0.700024 -1.500124)
			(end 0.700024 -1.500124)
			(stroke
				(width 0.1)
				(type default)
			)
			(layer "F.Fab")
		)
		(fp_line
			(start 0.700024 -1.500124)
			(end 0.700024 1.500124)
			(stroke
				(width 0.1)
				(type default)
			)
			(layer "F.Fab")
		)
		(pad "D" smd rect
			(at 1.119886 0 180)
			(size 1.016 1.2192)
			(layers "F.Cu" "F.Mask" "F.Paste")
			(net "LED_BIOS_DBG_MODE")
		)
		(pad "G" smd rect
			(at -1.119886 -0.999998 180)
			(size 1.016 1.2192)
			(layers "F.Cu" "F.Mask" "F.Paste")
			(net "LED_BIOS_DBG_MODE_N")
		)
		(pad "S" smd rect
			(at -1.119886 0.999998 180)
			(size 1.016 1.2192)
			(layers "F.Cu" "F.Mask" "F.Paste")
			(net "GND")
		)
	)
)
